# BASEBOARD_FAB2 (Tioga Pass) — schematic netlist excerpt (pin names and nets, part order shuffled) for the footprints in the layout excerpt that follows; sources: Cadence DE-HDL packaged netlist, KiCad conversion of Wiwynn_Tioga_Pass_MB.brd

EU4D2  NB3W1200L  IC  pkg LCC  page 102
  VDDA  = P3V3_DB1200_A
  GNDA  = GND
  NC(0)  = NC
  \100m_133m_n\  = FM_100M_N
  HBW_BYPASS_LOBW_N  = FM_HBW_BYPASS_LOWBW_N
  PWRGD_PWRDN_N  = FM_DB1200_PWRGD_R
  GND(0)  = GND
  VDDR  = P3V3_DB1200_R
  CLK_INP  = CLK_100M_DB1200_DP
  CLK_INN  = CLK_100M_DB1200_DN
  SA_0  = FM_DB1200_SMB_SA0
  SDA  = SMB_HOST_STBY_LVC3_SDA_R2
  SCL  = SMB_HOST_STBY_LVC3_SCL_R2
  SA_1  = FM_DB1200_SMB_SA1
  NC(2)  = NC
  NC(1)  = NC
  DIF_0P  = CLK_100M_CPU0_BCLK0_R_DP
  DIF_0N  = CLK_100M_CPU0_BCLK0_R_DN
  OE_0_N  = FM_DB1200ZL_BCLKS_EN_N
  OE_1_N  = FM_DB1200ZL_BCLKS_EN_N
  DIF_1P  = CLK_100M_CPU0_BCLK1_R_DP
  DIF_1N  = CLK_100M_CPU0_BCLK1_R_DN
  GND(1)  = GND
  VDD(0)  = P3V3_DB1200
  VDDIO(0)  = P3V3_DB1200
  DIF_2P  = CLK_100M_CPU0_BCLK2_R_DP
  DIF_2N  = CLK_100M_CPU0_BCLK2_R_DN
  OE_2_N  = FM_DB1200ZL_BCLKS_EN_N
  OE_3_N  = FM_CPU0_MCP_CLK_EN_N
  DIF_3P  = CLK_100M_CPU0_PE_REFCLK_R_DP
  DIF_3N  = CLK_100M_CPU0_PE_REFCLK_R_DN
  VDDIO(1)  = P3V3_DB1200
  GND(2)  = GND
  DIF_4P  = CLK_100M_CPU0_RC_REFCLK0_R_DP
  DIF_4N  = CLK_100M_CPU0_RC_REFCLK0_R_DN
  OE_4_N  = FM_CPU0_MCP_CLK_EN_N
  OE_5_N  = FM_CPU0_MCP_CLK_EN_N
  DIF_5P  = CLK_100M_CPU0_RC_REFCLK1_R_DP
  DIF_5N  = CLK_100M_CPU0_RC_REFCLK1_R_DN
  VDD(1)  = P3V3_DB1200
  GND(3)  = GND
  DIF_6P  = CLK_100M_CPU1_BCLK0_R_DP
  DIF_6N  = CLK_100M_CPU1_BCLK0_R_DN
  OE_6_N  = FM_DB1200ZL_BCLKS_EN_N
  OE_7_N  = FM_DB1200ZL_BCLKS_EN_N
  DIF_7P  = CLK_100M_CPU1_BCLK1_R_DP
  DIF_7N  = CLK_100M_CPU1_BCLK1_R_DN
  GND(4)  = GND
  VDDIO(2)  = P3V3_DB1200
  DIF_8P  = CLK_100M_CPU1_BCLK2_R_DP
  DIF_8N  = CLK_100M_CPU1_BCLK2_R_DN
  OE_8_N  = FM_DB1200ZL_BCLKS_EN_N
  OE_9_N  = FM_CPU1_MCP_CLK_EN_N
  DIF_9P  = CLK_100M_CPU1_PE_REFCLK_R_DP
  DIF_9N  = CLK_100M_CPU1_PE_REFCLK_R_DN
  VDDIO(3)  = P3V3_DB1200
  VDD(2)  = P3V3_DB1200
  GND(5)  = GND
  DIF_10P  = CLK_100M_CPU1_RC_REFCLK0_R_DP
  DIF_10N  = CLK_100M_CPU1_RC_REFCLK0_R_DN
  OE_10_N  = FM_CPU1_MCP_CLK_EN_N
  OE_11_N  = FM_CPU1_MCP_CLK_EN_N
  DIF_11P  = CLK_100M_CPU1_RC_REFCLK1_R_DP
  DIF_11N  = CLK_100M_CPU1_RC_REFCLK1_R_DN
  THPAD  = GND

(kicad_pcb
	(version 20260206)
	(generator "pcbnew")
	(generator_version "10.0")
	(general
		(thickness 1.6)
		(legacy_teardrops no)
	)
	(paper "A4")
	(title_block
		(title "Wiwynn_Tioga_Pass_MB.brd")
		(comment 1 "Tioga Pass / footprint 752 of 4770 (EU4D2), pads 35-51 of 65")
	)
	(layers
		(0 "F.Cu" signal "TOP")
		(4 "In1.Cu" signal "L2GND")
		(6 "In2.Cu" signal "L3")
		(8 "In3.Cu" signal "L4GND")
		(10 "In4.Cu" signal "L5")
		(12 "In5.Cu" signal "L6GND")
		(14 "In6.Cu" signal "L7VCC")
		(16 "In7.Cu" signal "L8VCC")
		(18 "In8.Cu" signal "L9GND")
		(20 "In9.Cu" signal "L10")
		(22 "In10.Cu" signal "L11GND")
		(24 "In11.Cu" signal "L12")
		(26 "In12.Cu" signal "L13GND")
		(2 "B.Cu" signal "BOTTOM")
		(9 "F.Adhes" user "F.Adhesive")
		(11 "B.Adhes" user "B.Adhesive")
		(13 "F.Paste" user "Package Geometry/Pastemask Top")
		(15 "B.Paste" user "Package Geometry/Pastemask Bottom")
		(5 "F.SilkS" user "Ref Des/Silkscreen Top")
		(7 "B.SilkS" user "Ref Des/Silkscreen Bottom")
		(1 "F.Mask" user "Board Geometry/Soldermask Top")
		(3 "B.Mask" user "Board Geometry/Soldermask Bottom")
		(17 "Dwgs.User" user "User.Drawings")
		(19 "Cmts.User" user "User.Comments")
		(21 "Eco1.User" user "User.Eco1")
		(23 "Eco2.User" user "User.Eco2")
		(25 "Edge.Cuts" user "Board Geometry/Outline")
		(27 "Margin" user)
		(31 "F.CrtYd" user "Package Geometry/Place Bound Top")
		(29 "B.CrtYd" user "Package Geometry/Place Bound Bottom")
		(35 "F.Fab" user "Ref Des/Assembly Top")
		(33 "B.Fab" user "Ref Des/Assembly Bottom")
	)
	(footprint ""
		(layer "F.Cu")
		(at 169.422826 -80.961992 90)
		(property "Reference" "EU4D2"
			(at -8.471662 1.773174 0)
			(unlocked yes)
			(layer "F.SilkS")
			(effects
				(font
					(size 0.7874 0.5842)
					(thickness 0.1524)
				)
				(justify left)
			)
		)
		(property "Value" ""
			(at 0 0 90)
			(layer "F.Fab")
			(effects
				(font
					(size 1.27 1.27)
				)
			)
		)
		(duplicate_pad_numbers_are_jumpers no)
		(pad "35" smd custom
			(at 4.3688 2.75082 90)
			(size 0.0762 0.0762)
			(layers "F.Cu" "F.Mask" "F.Paste")
			(net "CLK_100M_CPU0_RC_REFCLK0_R_DN")
			(options
				(clearance outline)
				(anchor circle)
			)
			(primitives
				(gr_poly
					(pts
						(xy 0.381 0.1524)
						(arc
							(start -0.2286 0.1524)
							(mid -0.381 0)
							(end -0.2286 -0.1524)
						)
						(xy 0.381 -0.1524)
					)
					(width 0)
					(fill yes)
				)
			)
		)
		(pad "36" smd custom
			(at 4.3688 2.250694 90)
			(size 0.0762 0.0762)
			(layers "F.Cu" "F.Mask" "F.Paste")
			(net "FM_CPU0_MCP_CLK_EN_N")
			(options
				(clearance outline)
				(anchor circle)
			)
			(primitives
				(gr_poly
					(pts
						(xy 0.381 0.1524)
						(arc
							(start -0.2286 0.1524)
							(mid -0.381 0)
							(end -0.2286 -0.1524)
						)
						(xy 0.381 -0.1524)
					)
					(width 0)
					(fill yes)
				)
			)
		)
		(pad "37" smd custom
			(at 4.3688 1.750568 90)
			(size 0.0762 0.0762)
			(layers "F.Cu" "F.Mask" "F.Paste")
			(net "FM_CPU0_MCP_CLK_EN_N")
			(options
				(clearance outline)
				(anchor circle)
			)
			(primitives
				(gr_poly
					(pts
						(xy 0.381 0.1524)
						(arc
							(start -0.2286 0.1524)
							(mid -0.381 0)
							(end -0.2286 -0.1524)
						)
						(xy 0.381 -0.1524)
					)
					(width 0)
					(fill yes)
				)
			)
		)
		(pad "38" smd custom
			(at 4.3688 1.250442 90)
			(size 0.0762 0.0762)
			(layers "F.Cu" "F.Mask" "F.Paste")
			(net "CLK_100M_CPU0_RC_REFCLK1_R_DP")
			(options
				(clearance outline)
				(anchor circle)
			)
			(primitives
				(gr_poly
					(pts
						(xy 0.381 0.1524)
						(arc
							(start -0.2286 0.1524)
							(mid -0.381 0)
							(end -0.2286 -0.1524)
						)
						(xy 0.381 -0.1524)
					)
					(width 0)
					(fill yes)
				)
			)
		)
		(pad "39" smd custom
			(at 4.3688 0.750316 90)
			(size 0.0762 0.0762)
			(layers "F.Cu" "F.Mask" "F.Paste")
			(net "CLK_100M_CPU0_RC_REFCLK1_R_DN")
			(options
				(clearance outline)
				(anchor circle)
			)
			(primitives
				(gr_poly
					(pts
						(xy 0.381 0.1524)
						(arc
							(start -0.2286 0.1524)
							(mid -0.381 0)
							(end -0.2286 -0.1524)
						)
						(xy 0.381 -0.1524)
					)
					(width 0)
					(fill yes)
				)
			)
		)
		(pad "40" smd custom
			(at 4.3688 0.25019 90)
			(size 0.0762 0.0762)
			(layers "F.Cu" "F.Mask" "F.Paste")
			(net "P3V3_DB1200")
			(options
				(clearance outline)
				(anchor circle)
			)
			(primitives
				(gr_poly
					(pts
						(xy 0.381 0.1524)
						(arc
							(start -0.2286 0.1524)
							(mid -0.381 0)
							(end -0.2286 -0.1524)
						)
						(xy 0.381 -0.1524)
					)
					(width 0)
					(fill yes)
				)
			)
		)
		(pad "41" smd custom
			(at 4.3688 -0.249936 90)
			(size 0.0762 0.0762)
			(layers "F.Cu" "F.Mask" "F.Paste")
			(net "GND")
			(options
				(clearance outline)
				(anchor circle)
			)
			(primitives
				(gr_poly
					(pts
						(xy 0.381 0.1524)
						(arc
							(start -0.2286 0.1524)
							(mid -0.381 0)
							(end -0.2286 -0.1524)
						)
						(xy 0.381 -0.1524)
					)
					(width 0)
					(fill yes)
				)
			)
		)
		(pad "42" smd custom
			(at 4.3688 -0.750062 90)
			(size 0.0762 0.0762)
			(layers "F.Cu" "F.Mask" "F.Paste")
			(net "CLK_100M_CPU1_BCLK0_R_DP")
			(options
				(clearance outline)
				(anchor circle)
			)
			(primitives
				(gr_poly
					(pts
						(xy 0.381 0.1524)
						(arc
							(start -0.2286 0.1524)
							(mid -0.381 0)
							(end -0.2286 -0.1524)
						)
						(xy 0.381 -0.1524)
					)
					(width 0)
					(fill yes)
				)
			)
		)
		(pad "43" smd custom
			(at 4.3688 -1.250188 90)
			(size 0.0762 0.0762)
			(layers "F.Cu" "F.Mask" "F.Paste")
			(net "CLK_100M_CPU1_BCLK0_R_DN")
			(options
				(clearance outline)
				(anchor circle)
			)
			(primitives
				(gr_poly
					(pts
						(xy 0.381 0.1524)
						(arc
							(start -0.2286 0.1524)
							(mid -0.381 0)
							(end -0.2286 -0.1524)
						)
						(xy 0.381 -0.1524)
					)
					(width 0)
					(fill yes)
				)
			)
		)
		(pad "44" smd custom
			(at 4.3688 -1.750314 90)
			(size 0.0762 0.0762)
			(layers "F.Cu" "F.Mask" "F.Paste")
			(net "FM_DB1200ZL_BCLKS_EN_N")
			(options
				(clearance outline)
				(anchor circle)
			)
			(primitives
				(gr_poly
					(pts
						(xy 0.381 0.1524)
						(arc
							(start -0.2286 0.1524)
							(mid -0.381 0)
							(end -0.2286 -0.1524)
						)
						(xy 0.381 -0.1524)
					)
					(width 0)
					(fill yes)
				)
			)
		)
		(pad "45" smd custom
			(at 4.3688 -2.25044 90)
			(size 0.0762 0.0762)
			(layers "F.Cu" "F.Mask" "F.Paste")
			(net "FM_DB1200ZL_BCLKS_EN_N")
			(options
				(clearance outline)
				(anchor circle)
			)
			(primitives
				(gr_poly
					(pts
						(xy 0.381 0.1524)
						(arc
							(start -0.2286 0.1524)
							(mid -0.381 0)
							(end -0.2286 -0.1524)
						)
						(xy 0.381 -0.1524)
					)
					(width 0)
					(fill yes)
				)
			)
		)
		(pad "46" smd custom
			(at 4.3688 -2.750566 90)
			(size 0.0762 0.0762)
			(layers "F.Cu" "F.Mask" "F.Paste")
			(net "CLK_100M_CPU1_BCLK1_R_DP")
			(options
				(clearance outline)
				(anchor circle)
			)
			(primitives
				(gr_poly
					(pts
						(xy 0.381 0.1524)
						(arc
							(start -0.2286 0.1524)
							(mid -0.381 0)
							(end -0.2286 -0.1524)
						)
						(xy 0.381 -0.1524)
					)
					(width 0)
					(fill yes)
				)
			)
		)
		(pad "47" smd custom
			(at 4.3688 -3.250692 90)
			(size 0.0762 0.0762)
			(layers "F.Cu" "F.Mask" "F.Paste")
			(net "CLK_100M_CPU1_BCLK1_R_DN")
			(options
				(clearance outline)
				(anchor circle)
			)
			(primitives
				(gr_poly
					(pts
						(xy 0.381 0.1524)
						(arc
							(start -0.2286 0.1524)
							(mid -0.381 0)
							(end -0.2286 -0.1524)
						)
						(xy 0.381 -0.1524)
					)
					(width 0)
					(fill yes)
				)
			)
		)
		(pad "48" smd custom
			(at 4.3688 -3.750818 90)
			(size 0.0762 0.0762)
			(layers "F.Cu" "F.Mask" "F.Paste")
			(net "GND")
			(options
				(clearance outline)
				(anchor circle)
			)
			(primitives
				(gr_poly
					(pts
						(xy 0.381 0.1524)
						(arc
							(start -0.2286 0.1524)
							(mid -0.381 0)
							(end -0.2286 -0.1524)
						)
						(xy 0.381 -0.1524)
					)
					(width 0)
					(fill yes)
				)
			)
		)
		(pad "49" smd custom
			(at 3.751072 -4.3688 90)
			(size 0.0762 0.0762)
			(layers "F.Cu" "F.Mask" "F.Paste")
			(net "P3V3_DB1200")
			(options
				(clearance outline)
				(anchor circle)
			)
			(primitives
				(gr_poly
					(pts
						(xy 0.1524 -0.381)
						(arc
							(start 0.1524 0.2286)
							(mid 0 0.381)
							(end -0.1524 0.2286)
						)
						(xy -0.1524 -0.381)
					)
					(width 0)
					(fill yes)
				)
			)
		)
		(pad "50" smd custom
			(at 3.250946 -4.3688 90)
			(size 0.0762 0.0762)
			(layers "F.Cu" "F.Mask" "F.Paste")
			(net "CLK_100M_CPU1_BCLK2_R_DP")
			(options
				(clearance outline)
				(anchor circle)
			)
			(primitives
				(gr_poly
					(pts
						(xy 0.1524 -0.381)
						(arc
							(start 0.1524 0.2286)
							(mid 0 0.381)
							(end -0.1524 0.2286)
						)
						(xy -0.1524 -0.381)
					)
					(width 0)
					(fill yes)
				)
			)
		)
		(pad "51" smd custom
			(at 2.75082 -4.3688 90)
			(size 0.0762 0.0762)
			(layers "F.Cu" "F.Mask" "F.Paste")
			(net "CLK_100M_CPU1_BCLK2_R_DN")
			(options
				(clearance outline)
				(anchor circle)
			)
			(primitives
				(gr_poly
					(pts
						(xy 0.1524 -0.381)
						(arc
							(start 0.1524 0.2286)
							(mid 0 0.381)
							(end -0.1524 0.2286)
						)
						(xy -0.1524 -0.381)
					)
					(width 0)
					(fill yes)
				)
			)
		)
	)
)
